# OAM_Pin list_Rev1.0.xlsx — Pin List (pin-map)
|  |  |  |  |  |  |  |  |  |  |  | Stack connector Dimensions |  |  | Per connector |  |  | Per  two connector |  |
| OCP Compute Accelerator Module Pin list |  |  |  |  |  |  |  |  | Connector family | Part Number | x (mm) | y (mm) | Area (mm2) | Diff Pairs | Single ended | Pin pairs density | Diff Pairs | Single ended |
| OCP Signal  name | Mezz Module Direction POV | OCP Signal Description | Voltage | OAM Baseboard implemention Recommendation | Total Diff Pair | Total SE pins | Conn0 or 1 | Molex | Mirror Mezz | 209311-1115 | 22 | 68 | 1496 | 172 | 0 | 0.11497326203208556 | 344 | 0 |
| P48V | Power Input | 44V-59.5V main voltage for high power applications. Up to 700W when Vin=>44V. Module should be able to operate at 40V to 44V but at lower power. | 44V-59.5V | Required for 48V based OAM. System should trigger power brake or power reduction to throttle OAMs when Vin <44v. |  | 16 | Conn0 |  |  |  |  |  |  |  |  |  |  |  |
| P12V1 | Power Input | 12V mandatory Board Infrastructure Power. Up to 50W | 12V | Required |  | 5 | Conn0 |  |  |  |  |  |  |  |  |  |  |  |
| P12V2 | Power Input | 12V main Power for low power applications. Up to 300W. For 12V motherboard/module designs, P12V1 and P12V2 can be shorted together for up to 350W  combined power | 12V | Required for P12V based OAM |  | 27 | Conn0 |  |  |  |  |  |  |  |  |  |  |  |
| P3V3 | Power Input | 3.3V Main Power. Up to 5W | 3.3V | Required |  | 2 | Conn0 |  |  |  |  |  |  |  |  |  |  |  |
| PVREF | Power Output | Low voltage output for GPU/ASIC sideband I/O reference on motherboard components.  Module should provision maximum 0.5A to be provided to motherboard. Vref  can be any value between 1.5V to 3.3V set as per GPU/ASIC sideband I/O voltage. Each OAM supplier will specify the actual Vref. | Vref | Required |  | 2 | Conn0 |  |  |  |  |  |  |  |  |  |  |  |
| PETp/n [15:0] | Output | PCIe or equivalent host link Transmit differential pairs. Module Transmit, Host Receive. Note: AC coupling caps must be placed on the motherboard side. |  | Required | 16 |  | Conn0 |  |  |  |  |  |  |  |  |  |  |  |
| PERp/n [15:0] | Input | PCIe or equivalent host link Receive differential pairs. Module Receive, Host Transmit. Note: AC coupling caps must be placed on the motherboard side. |  | Required | 16 |  | Conn0 |  |  |  |  |  |  |  |  |  |  |  |
| SERDES_1Tp/n [15:0] | Output | SerDes link 1 Transmit differential pairs. AC caps must be placed on Module/die (if required) |  | Required | 16 |  | Conn0 |  |  |  |  |  |  |  |  |  |  |  |
| SERDES_1Rp/n [15:0] | Input | SerDes link 1 Receive differential pairs. |  | Required | 16 |  | Conn0 |  |  |  |  |  |  |  |  |  |  |  |
| SERDES_2Tp/n [15:0] | Output | SerDes link 2 Transmit differential pairs. AC caps must be placed on Module/die (if required) |  | Required | 16 |  | Conn0 |  |  |  |  |  |  |  |  |  |  |  |
| SERDES_2Rp/n [15:0] | Input | SerDes link 2 Receive differential pairs. |  | Required | 16 |  | Conn0 |  |  |  |  |  |  |  |  |  |  |  |
| SERDES_3Tp/n[15:0] | Output | SerDes link 3 Transmit differential pairs. AC caps must be placed on Module/die (if required) |  | Required | 16 |  | Conn0 |  |  |  |  |  |  |  |  |  |  |  |
| SERDES_3Rp/n [15:0] | Input | SerDes link 3 Receive differential pairs. |  | Required | 16 |  | Conn0 |  |  |  |  |  |  |  |  |  |  |  |
| SERDES_4Tp/n[15:0] | Output | SerDes link 4Transmit differential pairs. AC caps must be placed on Module/die (if required) |  | Required | 16 |  | Conn1 |  |  |  |  |  |  |  |  |  |  |  |
| SERDES_4Rp/n [15:0] | Input | SerDes link 4 Receive differential pairs. |  | Required | 16 |  | Conn1 |  |  |  |  |  |  |  |  |  |  |  |
| SERDES_5Tp/n [15:0] | Output | SerDes link 5 Transmit differential pairs. AC caps must be placed on Module/die (if required) |  | Required | 16 |  | Conn1 |  |  |  |  |  |  |  |  |  |  |  |
| SERDES_5Rp/n [15:0] | Input | SerDes link 5 Receive differential pairs. |  | Required | 16 |  | Conn1 |  |  |  |  |  |  |  |  |  |  |  |
| SERDES_6Tp/n [15:0] | Output | SerDes link 6 Transmit differential pairs. AC caps must be placed on Module/die (if required) |  | Required | 16 |  | Conn1 |  |  |  |  |  |  |  |  |  |  |  |
| SERDES_6Rp/n [15:0] | Input | SerDes link 6 Receive differential pairs. |  | Required | 16 |  | Conn1 |  |  |  |  |  |  |  |  |  |  |  |
| SERDES_7Tp/n [15:0] | Output | SerDes Reserved Link Transmit differential pairs. Interconnect requirements defined by Module and System integrator. AC caps must be placed on the Motherboard (if Required) |  | Required | 16 |  | Conn1 |  |  |  |  |  |  |  |  |  |  |  |
| SERDES_7Rp/n [15:0] | Input | SerDes Reserved Link Receive differential pairs. Interconnect requirements defined by Module and System integrator. AC caps must be placed on the Motherboard (if Required) |  | Required | 16 |  | Conn1 |  |  |  |  |  |  |  |  |  |  |  |
| PE_REFCLKp/n | Input | PCIe Reference Clock. 100MHz PCIe Gen 5 compliant. |  | Required | 1 |  | Conn0 |  |  |  |  |  |  |  |  |  |  |  |
| AUX_100M_REFCLKp/n | Input | 100MHz PCIe Gen 5 compliant Auxiliary Reference Clock. |  | Required | 1 |  | Conn1 |  |  |  |  |  |  |  |  |  |  |  |
| AUX_156M_REFCLKp/n | Input | 156.25MHz Auxiliary Reference Clock |  | Required. Check with OAM product specification for compliance requirement. | 1 |  | Conn1 |  |  |  |  |  |  |  |  |  |  |  |
| DWN_REFCLKp/n | Output | Downstream Reference Clock. Vendor specific. |  | NC if not used | 1 |  | Conn1 |  |  |  |  |  |  |  |  |  |  |  |
| PERST# | Input | CEM Compliant PCIe Reset | 3.3V | Required |  | 1 | Conn0 |  |  |  |  |  |  |  |  |  |  |  |
| WARMRST# | Input | Warm Reset | Vref | NC for standard PCIe based system. Connect to Warmrst# from host for non-PCIe standard. |  | 1 | Conn0 |  |  |  |  |  |  |  |  |  |  |  |
| DWN_PERST# | Output | Down device PCIe Reset. Vendor specific. | 3.3V | NC if no down stream from OAM. |  | 1 | Conn1 |  |  |  |  |  |  |  |  |  |  |  |
| HOST_PWRGD | Input | Host power good. Active high when P48V, P12V1/P12V2, P3V3 voltages are stable and within specifications. This is considered the “Power Enable” signal for the module. | 3.3V | Required |  | 1 | Conn0 |  |  |  |  |  |  |  |  |  |  |  |
| MODULE_PWRGD | Output | Module power good. Active high when the module has completed its own power up sequence and is ready for PERST# de-assertion | 3.3V | Required |  | 1 | Conn0 |  |  |  |  |  |  |  |  |  |  |  |
| PWRBRK# | Input | Emergency power reduction. CEM Compliant Power Break | 3.3V | Required |  | 1 | Conn0 |  |  |  |  |  |  |  |  |  |  |  |
| PWRRDT#[1:0] | Input | Power Reduction GPIO to instruct Oam to go certain stage to reduce power 11 - default state L0, normal power 10 - L1, 1st level power reduction.  01 - L2, 2nd level power reduction.  00 - L3, max power reduction.  Details defined by specific OAM product specification. | 3.3V | Required |  | 2 | Conn1 |  |  |  |  |  |  |  |  |  |  |  |
| THERMTRIP# | Output | Catastrophic thermal event for module components. Active low and latched by the Module logic. Released until motherboard power cycles the module input voltages | 3.3V | Required |  | 1 | Conn1 |  |  |  |  |  |  |  |  |  |  |  |
| MODULE_ID[4:0] | Input | Module node identifier (e.g. Module #0, #1,…#n). Module has weak PU to drive to 1 by default. |  | Required.  Tied to GND through 1K resistor on baseboard for logic 0, leave open for logic 1 |  | 5 | Conn0 |  |  |  |  |  |  |  |  |  |  |  |
| LINK_CONFIG[4:0] | Input | Mezz Module Host Interface/SerDes Link Configuration and topology. See link config table for details. Module has weak PU to Vref to drive high by default. |  | Required. Tied to GND through 1K resistor on baseboard for logic 0, leave open for logic 1 |  | 5 | Conn1 |  |  |  |  |  |  |  |  |  |  |  |
| PE_BIF[1:0] | Output | x16 Host Interface Bifurcation Configuration.  00 = one x16 PCIe host interface 01 = bifurcation into two x8 PCIe host interfaces 10 = bifurcation into four x4 PCIe host interfaces 11 = reserved Vref based when drive to high. |  | Required. Add level shift. |  | 2 | Conn1 |  |  |  |  |  |  |  |  |  |  |  |
| PLINK_CAP | Output | "P" Port Module Capability support:  '0' = PCIe only support '1' = Alternate protocol supported The host system requests an alternate host link protocol by pulling up LINK_CONFIG[0] and the Module informs the system of protocol support on the "P" link via this pin. If the module only supports PCIe as host, this signal is PD on the module. | Vref | Required. Add level shift. |  | 1 | Conn1 |  |  |  |  |  |  |  |  |  |  |  |
| SMBus_SLV_D | Bi-directional | Slave SMBus data. | 3.3V | Required. PU on baseboard and connect to BMC |  | 1 | Conn0 |  |  |  |  |  |  |  |  |  |  |  |
| SMBus_SLV_CLK | Input | Slave SMBus clock | 3.3V | Required. PU on baseboard and connect to BMC |  | 1 | Conn0 |  |  |  |  |  |  |  |  |  |  |  |
| SLV_ALERT# | Output | Slave  alert indication. | 3.3V | Required. PU on baseboard and connect to BMC |  | 1 | Conn0 |  |  |  |  |  |  |  |  |  |  |  |
| I2C_D | Bi-directional | Master I2C/SMBus data . PU on OAM. | Vref | Required. Add level shift to 3.3V. OAM0 will need DEMUX to connect to baseboard FRU with BMC. |  | 1 | Conn0 |  |  |  |  |  |  |  |  |  |  |  |
| I2C _CLK | Output | Master I2C/SMBus clock.  PU on OAM. | Vref | Required. Add level shift to 3.3V. OAM0 will need DEMUX to connect to baseboard FRU with BMC. |  | 1 | Conn0 |  |  |  |  |  |  |  |  |  |  |  |
| UART_TXD | Output | Serial Port Transmit | 3.3V | Required. Suggest to connect to UART2usb bridge(the bridge usb port connects to BMC usb) |  | 1 | Conn0 |  |  |  |  |  |  |  |  |  |  |  |
| UART_RXD | Input | Serial Port Receive | 3.3V | Required. Suggest to connect to UART2usb bridge(the bridge usb port connects to BMC usb) |  | 1 | Conn0 |  |  |  |  |  |  |  |  |  |  |  |
| JTAG0_TRST | Input | Low Voltage ASIC/GPU JTAG Test Reset | Vref | Required |  | 1 | Conn0 |  |  |  |  |  |  |  |  |  |  |  |
| JTAG0_TMS | Input | Low Voltage ASIC/GPU JTAG Test Mode Select | Vref | Required |  | 1 | Conn0 |  |  |  |  |  |  |  |  |  |  |  |
| JTAG0_TCK | Input | Low Voltage ASIC/GPU JTAG Test Clock | Vref | Required |  | 1 | Conn0 |  |  |  |  |  |  |  |  |  |  |  |
| JTAG0_TDO | Output | Low Voltage ASIC/GPU JTAG Test Output | Vref | Required |  | 1 | Conn0 |  |  |  |  |  |  |  |  |  |  |  |
| JTAG0 _TDI | Input | Low Voltage ASIC/GPU JTAG Test Input | Vref | Required |  | 1 | Conn0 |  |  |  |  |  |  |  |  |  |  |  |
| JTAG1 _TRST | Input | High Voltage JTAG Test Reset | 3.3V | Optional |  | 1 | Conn1 |  |  |  |  |  |  |  |  |  |  |  |
| JTAG1 _TMS | Input | High Voltage JTAG Test Mode Select | 3.3V | Optional |  | 1 | Conn1 |  |  |  |  |  |  |  |  |  |  |  |
| JTAG1 _TCK | Input | High Voltage JTAG Test Clock | 3.3V | Optional |  | 1 | Conn1 |  |  |  |  |  |  |  |  |  |  |  |
| JTAG1 _TDO | Output | High Voltage JTAG Test Output | 3.3V | Optional |  | 1 | Conn1 |  |  |  |  |  |  |  |  |  |  |  |
| JTAG1 _TDI | Input | High Voltage JTAG Test Input | 3.3V | Optional |  | 1 | Conn1 |  |  |  |  |  |  |  |  |  |  |  |
| CONN1_INITMODE | Output | QSFP-DD Connector 1 Module Initialization mode | Vref | add level shift and connect to QSFP-DD conn if any expansion |  | 1 | Conn1 |  |  |  |  |  |  |  |  |  |  |  |
| CONN1_INT# | Input | QSFP-DD Connector 1 Module Interrupt | Vref | add level shift and connect to QSFP-DD conn if any expansion |  | 1 | Conn1 |  |  |  |  |  |  |  |  |  |  |  |
| CONN1_MODPRS# | Input | QSFP-DD Connector 1 Module Present | Vref | add level shift and connect to QSFP-DD conn if any expansion |  | 1 | Conn1 |  |  |  |  |  |  |  |  |  |  |  |
| CONN1_MODSEL# | Output | QSFP-DD Connector 1 Module Select | Vref | add level shift and connect to QSFP-DD conn if any expansion |  | 1 | Conn1 |  |  |  |  |  |  |  |  |  |  |  |
| CONN1_RESET# | Output | QSFP-DD Connector 1 Module Reset | Vref | add level shift and connect to QSFP-DD conn if any expansion |  | 1 | Conn1 |  |  |  |  |  |  |  |  |  |  |  |
| CONN1_GREEN_LED | Output | QSFP-DD Connector 1 GREEN STATUS LED | Vref | add level shift and connect to QSFP-DD conn if any expansion. NC if not used. |  | 1 | Conn1 |  |  |  |  |  |  |  |  |  |  |  |
| CONN1_YELLOW_LED | Output | QSFP-DD Connector 1 YELLOW STATUS LED | Vref | add level shift and connect to QSFP-DD conn if any expansion. NC if not used. |  | 1 | Conn1 |  |  |  |  |  |  |  |  |  |  |  |
| CONN2_INITMODE | Output | QSFP-DD Connector 2 Module Initialization mode | Vref | add level shift and connect to QSFP-DD conn if any expansion |  | 1 | Conn1 |  |  |  |  |  |  |  |  |  |  |  |
| CONN2_INT# | Input | QSFP-DD Connector 2 Module Interrupt | Vref | add level shift and connect to QSFP-DD conn if any expansion |  | 1 | Conn1 |  |  |  |  |  |  |  |  |  |  |  |
| CONN2_MODPRS# | Input | QSFP-DD Connector 2 Module Present | Vref | add level shift and connect to QSFP-DD conn if any expansion |  | 1 | Conn1 |  |  |  |  |  |  |  |  |  |  |  |
| CONN2_MODSEL# | Output | QSFP-DD Connector 2 Module Select | Vref | add level shift and connect to QSFP-DD conn if any expansion |  | 1 | Conn1 |  |  |  |  |  |  |  |  |  |  |  |
| CONN2_RESET# | Output | QSFP-DD Connector 2 Module Reset | Vref | add level shift and connect to QSFP-DD conn if any expansion |  | 1 | Conn1 |  |  |  |  |  |  |  |  |  |  |  |
| CONN2_GREEN_LED | Output | QSFP-DD Connector 2 GREEN STATUS LED | Vref | add level shift and connect to QSFP-DD conn if any expansion. NC if not used. |  | 1 | Conn1 |  |  |  |  |  |  |  |  |  |  |  |
| CONN2_YELLOW_LED | Output | QSFP-DD Connector 2 YELLOW STATUS LED | Vref | add level shift and connect to QSFP-DD conn if any expansion. NC if not used. |  | 1 | Conn1 |  |  |  |  |  |  |  |  |  |  |  |
| PRSNT0# | Output | Module present pin connector 0. Tied to GND through 1K resistor on module side. |  | Weak PU on baseboard side. |  | 1 | Conn0 |  |  |  |  |  |  |  |  |  |  |  |
| PRSNT1# | Output | Module present pin connector 1. Tied to GND through 1K resistor on module side |  | Weak PU on baseboard side. |  | 1 | Conn1 |  |  |  |  |  |  |  |  |  |  |  |
| SCALE_DEBUG_EN | Output | At-scale debug enable on the module. Isolates any motherboard JTAG debug path when logic High | 3.3V | Required |  | 1 | Conn1 |  |  |  |  |  |  |  |  |  |  |  |
| DEBUG_PORT_PRSNT# | Input | Presence signal for debug port in baseboard. Notifies logic in the module the debug access is being used by the baseboard debug connector. Debug port on baseboard present when logic low. | Vref? | Strong PU on baseboard side. |  | 1 | Conn1 |  |  |  |  |  |  |  |  |  |  |  |
| MNGMT_LINK0Tp/n | Output | Vendor specific module to module management link port 0 transmit |  | Required for some accelerators. Check with accelerator vendor. | 1 |  | Conn1 |  |  |  |  |  |  |  |  |  |  |  |
| MNGMT_LINK0Rp/n | Input | Vendor specific module to module management link port 0 receive |  | Required for some accelerators. Check with accelerator vendor. | 1 |  | Conn1 |  |  |  |  |  |  |  |  |  |  |  |
| MNGMT_LINK1Tp/n | Output | Vendor specific module to module management link port 1 transmit |  | Required for some accelerators. Check with accelerator vendor. | 1 |  | Conn1 |  |  |  |  |  |  |  |  |  |  |  |
| MNGMT_LINK1Rp/n | Input | Vendor specific module to module management link port 1 receive |  | Required for some accelerators. Check with accelerator vendor. | 1 |  | Conn1 |  |  |  |  |  |  |  |  |  |  |  |
| TEST0 | Input |  | Vref | Demux all 8 OAMs' test pin |  | 1 | Conn0 |  |  |  |  |  |  |  |  |  |  |  |
| TEST1 | Input |  | Vref | Demux all 8 OAMs' test pin |  |  | Conn0 |  |  |  |  |  |  |  |  |  |  |  |
| TEST2 | Input |  | Vref | Demux all 8 OAMs' test pin |  |  | Conn0 |  |  |  |  |  |  |  |  |  |  |  |
| TEST3 | Input |  | Vref | Demux all 8 OAMs' test pin |  |  | Conn0 |  |  |  |  |  |  |  |  |  |  |  |
| TEST4 | Input |  | Vref | Demux all 8 OAMs' test pin |  | 4 | Conn0 |  |  |  |  |  |  |  |  |  |  |  |
| TEST5 | I/O |  | Vref | Demux all 8 OAMs' test pin |  | 1 | Conn0 |  |  |  |  |  |  |  |  |  |  |  |
| TEST6 | I/O |  | Vref | Demux all 8 OAMs' test pin |  | 1 | Conn0 |  |  |  |  |  |  |  |  |  |  |  |
| TEST7 | Output |  | Vref | Demux all 8 OAMs' test pin |  | 1 | Conn0 |  |  |  |  |  |  |  |  |  |  |  |
| TEST8 | Input |  | Vref | Demux all 8 OAMs' test pin |  | 1 | Conn0 |  |  |  |  |  |  |  |  |  |  |  |
| TEST9 | Input |  | Vref | Demux all 8 OAMs' test pin |  | 1 | Conn0 |  |  |  |  |  |  |  |  |  |  |  |
| TEST10 | Input |  | Vref | Demux all 8 OAMs' test pin |  | 1 | Conn1 |  |  |  |  |  |  |  |  |  |  |  |
| TEST11 | Output |  | Vref | Demux all 8 OAMs' test pin |  | 1 | Conn1 |  |  |  |  |  |  |  |  |  |  |  |
| TEST12 | Input |  | Vref | Demux all 8 OAMs' test pin |  | 1 | Conn1 |  |  |  |  |  |  |  |  |  |  |  |
| TEST13 | Input |  | Vref | Demux all 8 OAMs' test pin |  | 1 | Conn1 |  |  |  |  |  |  |  |  |  |  |  |
| TEST14 | Input |  | Vref | Demux all 8 OAMs' test pin |  | 1 | Conn1 |  |  |  |  |  |  |  |  |  |  |  |
| MANF_MODE# | Input | Manufacturing Mode 1: Normal operation 0: Module enter into manufacturing mode | 3.3V | Tie all OAMs MANF_MODE# together and connect to a jumper |  | 1 | Conn0 |  |  |  |  |  |  |  |  |  |  |  |
| FW_RECOVERY# | Input | On board manageability boot recovery mode 1: Normal operation 0: Firmware Recovery boot mode | 3.3V | Tie all FW_recovery# together and connect to a jumper |  | 1 | Conn0 |  |  |  |  |  |  |  |  |  |  |  |
| TEST_MODE# | Input | Compliance Test Mode 1: Normal operation 0: ASIC/GPU enter into electrical compliance mode | Vref | Tie all Test_mode# together and connect to a jumper |  | 1 | Conn0 |  |  |  |  |  |  |  |  |  |  |  |
| RFU |  | Reserved for future use |  |  |  | 4 | Conn0 |  |  |  |  |  |  |  |  |  |  |  |
| RFU |  | Reserved for future use |  |  |  | 23 | Conn1 |  |  |  |  |  |  |  |  |  |  |  |
| Sub Total |  |  |  |  | 264 | 83 |  |  |  |  |  |  |  |  |  |  |  |  |
| Total pin locations |  |  |  |  | 611 |  |  |  |  |  |  |  |  |  |  |  |  |  |
| Total in diff pairs |  |  |  |  | 305.5 |  |  |  |  |  |  |  |  |  |  |  |  |  |
